FILE_TYPE = MACRO_DRAWING;
SET COLOR_WIRE YELLOW;
SET COLOR_PROP ORANGE;
SET COLOR_DOT WHITE;
SET COLOR_ARC YELLOW;
SET COLOR_BODY GREEN;
SET COLOR_NOTE PURPLE;
SET PROP_DISPLAY VALUE;
SET PAGE_NUMBER P1;
FORCEADD SYNONYM..1
(1850 2050);
PAINT MONO (1850 2050);
FORCEPROP 2 LAST PATH 4P
J 0
(1850 2150);
DISPLAY 0.872340 (1850 2150);
PAINT YELLOW (1850 2150);
FORCEPROP 1 LAST NEEDS_NO_SIZE TRUE
J 0
(1875 2125);
DISPLAY 0.872340 (1875 2125);
PAINT MONO (1875 2125);
DISPLAY INVISIBLE (1875 2125);
FORCEPROP 1 LAST BODY_TYPE PLUMBING
J 0
(1850 2100);
DISPLAY 0.872340 (1850 2100);
PAINT GREEN (1850 2100);
DISPLAY INVISIBLE (1850 2100);
FORCEPROP 2 LAST CDS_LIB mstr_standard
J 0
(1850 2050);
DISPLAY 0.851064 (1850 2050);
DISPLAY INVISIBLE (1850 2050);
FORCEADD DRAWING..2
(1275 1750);
PAINT MONO (1275 1750);
FORCEPROP 1 LAST LAST_MODIFIED Tue Oct 25 13:05:01 2011
J 0
(1575 1500);
DISPLAY 0.872340 (1575 1500);
PAINT GREEN (1575 1500);
FORCEPROP 1 LAST TITLE P12V
J 0
(1325 1700);
DISPLAY 0.872340 (1325 1700);
PAINT GREEN (1325 1700);
FORCEPROP 1 LAST ABBREV P12V
J 0
(1325 1650);
DISPLAY 0.872340 (1325 1650);
PAINT GREEN (1325 1650);
WIRE 16 -1 (1800 2050)(1200 2050);
FORCEPROP 2 LAST SIG_NAME G\I
J 0
(1025 2060);
DISPLAY 0.872340 (1025 2060);
PAINT MONO (1025 2060);
WIRE 0 -1 (1900 2050)(2050 2050);
FORCEPROP 2 LAST SIG_NAME P12V \G
J 0
(2075 2085);
DISPLAY 0.872340 (2075 2085);
PAINT MONO (2075 2085);
QUIT
